(kicad_pcb
	(version 20260206)
	(generator "pcbnew")
	(generator_version "10.0")
	(general
		(thickness 1.6)
		(legacy_teardrops no)
	)
	(paper "A4")
	(title_block
		(title "baseboard — 13948-1b.1110WZS1818.brd")
		(comment 1 "Honey Badger (Wiwynn) / footprints 1342-1349 of 2523")
	)
	(layers
		(0 "F.Cu" signal "TOP")
		(4 "In1.Cu" signal "L2GND")
		(6 "In2.Cu" signal "L3")
		(8 "In3.Cu" signal "L4VCC")
		(10 "In4.Cu" signal "L5VCC")
		(12 "In5.Cu" signal "L6")
		(14 "In6.Cu" signal "L7GND")
		(2 "B.Cu" signal "BOTTOM")
		(9 "F.Adhes" user "F.Adhesive")
		(11 "B.Adhes" user "B.Adhesive")
		(13 "F.Paste" user "Package Geometry/Pastemask Top")
		(15 "B.Paste" user "Package Geometry/Pastemask Bottom")
		(5 "F.SilkS" user "Ref Des/Silkscreen Top")
		(7 "B.SilkS" user "Ref Des/Silkscreen Bottom")
		(1 "F.Mask" user "Board Geometry/Soldermask Top")
		(3 "B.Mask" user "Board Geometry/Soldermask Bottom")
		(17 "Dwgs.User" user "User.Drawings")
		(19 "Cmts.User" user "User.Comments")
		(21 "Eco1.User" user "User.Eco1")
		(23 "Eco2.User" user "User.Eco2")
		(25 "Edge.Cuts" user "Board Geometry/Outline")
		(27 "Margin" user)
		(31 "F.CrtYd" user "Package Geometry/Place Bound Top")
		(29 "B.CrtYd" user "Package Geometry/Place Bound Bottom")
		(35 "F.Fab" user "Ref Des/Assembly Top")
		(33 "B.Fab" user "Ref Des/Assembly Bottom")
	)
	(footprint ""
		(layer "F.Cu")
		(at 86.67877 -114.25936 90)
		(property "Reference" "SC1107"
			(at 0 0 90)
			(layer "F.SilkS")
			(hide yes)
			(effects
				(font
					(size 1.27 1.27)
				)
			)
		)
		(property "Value" "SCD1U16V2KX-3GP"
			(at 1.1811 -2.7051 90)
			(unlocked yes)
			(layer "F.Fab")
			(hide yes)
			(effects
				(font
					(size 1.016 1.016)
					(thickness 0.1524)
				)
			)
		)
		(property "Device Type" "C402H22"
			(at 1.1811 -4.2291 90)
			(unlocked yes)
			(layer "F.Fab")
			(hide yes)
			(effects
				(font
					(size 1.016 1.016)
					(thickness 0.1524)
				)
			)
		)
		(duplicate_pad_numbers_are_jumpers no)
		(fp_rect
			(start -0.4318 0.9525)
			(end 0.4318 -0.9525)
			(stroke
				(width 0)
				(type default)
			)
			(fill no)
			(layer "F.CrtYd")
		)
		(fp_rect
			(start -0.4318 0.9525)
			(end 0.4318 -0.9525)
			(stroke
				(width 0)
				(type default)
			)
			(fill no)
			(layer "F.Fab")
		)
		(pad "1" smd custom
			(at 0 -0.4445 90)
			(size 0.1524 0.1524)
			(layers "F.Cu" "F.Mask" "F.Paste")
			(net "P1V8_E")
			(options
				(clearance outline)
				(anchor circle)
			)
			(primitives
				(gr_poly
					(pts
						(arc
							(start 0.3048 -0.2032)
							(mid 0.275042 -0.275042)
							(end 0.2032 -0.3048)
						)
						(arc
							(start -0.2032 -0.3048)
							(mid -0.275042 -0.275042)
							(end -0.3048 -0.2032)
						)
						(arc
							(start -0.3048 0.2032)
							(mid -0.275042 0.275042)
							(end -0.2032 0.3048)
						)
						(arc
							(start 0.2032 0.3048)
							(mid 0.275042 0.275042)
							(end 0.3048 0.2032)
						)
					)
					(width 0)
					(fill yes)
				)
			)
		)
		(pad "2" smd custom
			(at 0 0.4445 90)
			(size 0.1524 0.1524)
			(layers "F.Cu" "F.Mask" "F.Paste")
			(net "GND")
			(options
				(clearance outline)
				(anchor circle)
			)
			(primitives
				(gr_poly
					(pts
						(arc
							(start 0.3048 -0.2032)
							(mid 0.275042 -0.275042)
							(end 0.2032 -0.3048)
						)
						(arc
							(start -0.2032 -0.3048)
							(mid -0.275042 -0.275042)
							(end -0.3048 -0.2032)
						)
						(arc
							(start -0.3048 0.2032)
							(mid -0.275042 0.275042)
							(end -0.2032 0.3048)
						)
						(arc
							(start 0.2032 0.3048)
							(mid 0.275042 0.275042)
							(end 0.3048 0.2032)
						)
					)
					(width 0)
					(fill yes)
				)
			)
		)
	)
	(footprint ""
		(layer "F.Cu")
		(at 116.713 -28.321 180)
		(property "Reference" "SR671"
			(at 0 0 180)
			(layer "F.SilkS")
			(hide yes)
			(effects
				(font
					(size 1.27 1.27)
				)
			)
		)
		(property "Value" "4K7R2F-GP"
			(at 0.064008 -3.993896 180)
			(unlocked yes)
			(layer "F.Fab")
			(hide yes)
			(effects
				(font
					(size 1.016 1.016)
					(thickness 0.1524)
				)
			)
		)
		(property "Device Type" "R402H16"
			(at 0.064008 -5.517896 180)
			(unlocked yes)
			(layer "F.Fab")
			(hide yes)
			(effects
				(font
					(size 1.016 1.016)
					(thickness 0.1524)
				)
			)
		)
		(duplicate_pad_numbers_are_jumpers no)
		(fp_line
			(start 0.508 -0.9398)
			(end -0.508 -0.9398)
			(stroke
				(width 0.1524)
				(type default)
			)
			(layer "F.SilkS")
		)
		(fp_line
			(start -0.508 -0.9398)
			(end -0.508 0.9398)
			(stroke
				(width 0.1524)
				(type default)
			)
			(layer "F.SilkS")
		)
		(fp_rect
			(start -0.508 0.9398)
			(end 0.508 -0.9398)
			(stroke
				(width 0)
				(type default)
			)
			(fill no)
			(layer "F.CrtYd")
		)
		(fp_rect
			(start -0.508 0.9398)
			(end 0.508 -0.9398)
			(stroke
				(width 0)
				(type default)
			)
			(fill no)
			(layer "F.Fab")
		)
		(pad "1" smd custom
			(at 0 -0.4445 180)
			(size 0.1397 0.1397)
			(layers "F.Cu" "F.Mask" "F.Paste")
			(net "P1V8_C")
			(options
				(clearance outline)
				(anchor circle)
			)
			(primitives
				(gr_poly
					(pts
						(arc
							(start -0.1778 -0.2794)
							(mid -0.249642 -0.249642)
							(end -0.2794 -0.1778)
						)
						(arc
							(start -0.2794 0.1778)
							(mid -0.249642 0.249642)
							(end -0.1778 0.2794)
						)
						(arc
							(start 0.1778 0.2794)
							(mid 0.249642 0.249642)
							(end 0.2794 0.1778)
						)
						(arc
							(start 0.2794 -0.1778)
							(mid 0.249642 -0.249642)
							(end 0.1778 -0.2794)
						)
					)
					(width 0)
					(fill yes)
				)
			)
		)
		(pad "2" smd custom
			(at 0 0.4445 180)
			(size 0.1397 0.1397)
			(layers "F.Cu" "F.Mask" "F.Paste")
			(net "SYS_HALT1#")
			(options
				(clearance outline)
				(anchor circle)
			)
			(primitives
				(gr_poly
					(pts
						(arc
							(start -0.1778 -0.2794)
							(mid -0.249642 -0.249642)
							(end -0.2794 -0.1778)
						)
						(arc
							(start -0.2794 0.1778)
							(mid -0.249642 0.249642)
							(end -0.1778 0.2794)
						)
						(arc
							(start 0.1778 0.2794)
							(mid 0.249642 0.249642)
							(end 0.2794 0.1778)
						)
						(arc
							(start 0.2794 -0.1778)
							(mid 0.249642 -0.249642)
							(end 0.1778 -0.2794)
						)
					)
					(width 0)
					(fill yes)
				)
			)
		)
	)
	(footprint ""
		(layer "F.Cu")
		(at 103.105966 -62.3316 90)
		(property "Reference" "SC918"
			(at 0 0 90)
			(layer "F.SilkS")
			(hide yes)
			(effects
				(font
					(size 1.27 1.27)
				)
			)
		)
		(property "Value" "SCD1U6D3V1KX-GP"
			(at -2.8321 -1.7399 90)
			(unlocked yes)
			(layer "F.Fab")
			(hide yes)
			(effects
				(font
					(size 1.016 1.016)
					(thickness 0.1524)
				)
			)
		)
		(property "Device Type" "C0201H13"
			(at -2.8321 -3.2639 90)
			(unlocked yes)
			(layer "F.Fab")
			(hide yes)
			(effects
				(font
					(size 1.016 1.016)
					(thickness 0.1524)
				)
			)
		)
		(duplicate_pad_numbers_are_jumpers no)
		(fp_rect
			(start -0.2794 0.6477)
			(end 0.2794 -0.6477)
			(stroke
				(width 0)
				(type default)
			)
			(fill no)
			(layer "F.CrtYd")
		)
		(fp_rect
			(start -0.2794 0.6477)
			(end 0.2794 -0.6477)
			(stroke
				(width 0)
				(type default)
			)
			(fill no)
			(layer "F.Fab")
		)
		(pad "1" smd custom
			(at 0 -0.2794 90)
			(size 0.0762 0.0762)
			(layers "F.Cu" "F.Mask" "F.Paste")
			(net "HM40ADC_VDDA")
			(options
				(clearance outline)
				(anchor circle)
			)
			(primitives
				(gr_poly
					(pts
						(arc
							(start 0.1524 -0.127)
							(mid 0.137521 -0.162921)
							(end 0.1016 -0.1778)
						)
						(arc
							(start -0.1016 -0.1778)
							(mid -0.137521 -0.162921)
							(end -0.1524 -0.127)
						)
						(arc
							(start -0.1524 0.127)
							(mid -0.137521 0.162921)
							(end -0.1016 0.1778)
						)
						(arc
							(start 0.1016 0.1778)
							(mid 0.137521 0.162921)
							(end 0.1524 0.127)
						)
					)
					(width 0)
					(fill yes)
				)
			)
		)
		(pad "2" smd custom
			(at 0 0.2794 90)
			(size 0.0762 0.0762)
			(layers "F.Cu" "F.Mask" "F.Paste")
			(net "GND")
			(options
				(clearance outline)
				(anchor circle)
			)
			(primitives
				(gr_poly
					(pts
						(arc
							(start 0.1524 -0.127)
							(mid 0.137521 -0.162921)
							(end 0.1016 -0.1778)
						)
						(arc
							(start -0.1016 -0.1778)
							(mid -0.137521 -0.162921)
							(end -0.1524 -0.127)
						)
						(arc
							(start -0.1524 0.127)
							(mid -0.137521 0.162921)
							(end -0.1016 0.1778)
						)
						(arc
							(start 0.1016 0.1778)
							(mid 0.137521 0.162921)
							(end 0.1524 0.127)
						)
					)
					(width 0)
					(fill yes)
				)
			)
		)
	)
	(footprint ""
		(layer "F.Cu")
		(at 80.772 -33.401)
		(property "Reference" "SC957"
			(at 0 0 0)
			(layer "F.SilkS")
			(hide yes)
			(effects
				(font
					(size 1.27 1.27)
				)
			)
		)
		(property "Value" "SC100U6D3V0MX-2GP"
			(at -0.00254 -4.78536 0)
			(unlocked yes)
			(layer "F.Fab")
			(hide yes)
			(effects
				(font
					(size 1.016 1.016)
					(thickness 0.1524)
				)
			)
		)
		(property "Device Type" "C1210H107"
			(at -0.00254 -6.38048 0)
			(unlocked yes)
			(layer "F.Fab")
			(hide yes)
			(effects
				(font
					(size 1.016 1.016)
					(thickness 0.1524)
				)
			)
		)
		(duplicate_pad_numbers_are_jumpers no)
		(fp_line
			(start -1.5748 -2.3368)
			(end -1.5748 -0.762)
			(stroke
				(width 0.1524)
				(type default)
			)
			(layer "F.SilkS")
		)
		(fp_line
			(start -1.5748 0.762)
			(end -1.5748 2.3368)
			(stroke
				(width 0.1524)
				(type default)
			)
			(layer "F.SilkS")
		)
		(fp_line
			(start -1.5748 2.3368)
			(end 1.5748 2.3368)
			(stroke
				(width 0.1524)
				(type default)
			)
			(layer "F.SilkS")
		)
		(fp_line
			(start 1.5748 -2.3368)
			(end -1.5748 -2.3368)
			(stroke
				(width 0.1524)
				(type default)
			)
			(layer "F.SilkS")
		)
		(fp_line
			(start 1.5748 -0.762)
			(end 1.5748 -2.3368)
			(stroke
				(width 0.1524)
				(type default)
			)
			(layer "F.SilkS")
		)
		(fp_line
			(start 1.5748 2.3368)
			(end 1.5748 0.762)
			(stroke
				(width 0.1524)
				(type default)
			)
			(layer "F.SilkS")
		)
		(fp_rect
			(start -1.651 2.413)
			(end 1.651 -2.413)
			(stroke
				(width 0)
				(type default)
			)
			(fill no)
			(layer "F.CrtYd")
		)
		(fp_poly
			(pts
				(xy 1.651 2.413) (xy 1.651 -2.413) (xy -1.651 -2.413) (xy -1.651 2.413)
			)
			(stroke
				(width 0)
				(type default)
			)
			(fill no)
			(layer "F.Fab")
		)
		(pad "1" smd rect
			(at 0 -1.4732)
			(size 2.794 1.397)
			(layers "F.Cu" "F.Mask" "F.Paste")
			(net "GND")
		)
		(pad "2" smd rect
			(at 0 1.4732)
			(size 2.794 1.397)
			(layers "F.Cu" "F.Mask" "F.Paste")
			(net "SAS0_AVDD")
		)
	)
	(footprint ""
		(layer "F.Cu")
		(at 274.193 -180.721 90)
		(property "Reference" "R347"
			(at 0 0 90)
			(layer "F.SilkS")
			(hide yes)
			(effects
				(font
					(size 1.27 1.27)
				)
			)
		)
		(property "Value" "3K3R2F-2-GP"
			(at 0.064008 -3.993896 90)
			(unlocked yes)
			(layer "F.Fab")
			(hide yes)
			(effects
				(font
					(size 1.016 1.016)
					(thickness 0.1524)
				)
			)
		)
		(property "Device Type" "R402H16"
			(at 0.064008 -5.517896 90)
			(unlocked yes)
			(layer "F.Fab")
			(hide yes)
			(effects
				(font
					(size 1.016 1.016)
					(thickness 0.1524)
				)
			)
		)
		(duplicate_pad_numbers_are_jumpers no)
		(fp_line
			(start 0.508 -0.9398)
			(end -0.508 -0.9398)
			(stroke
				(width 0.1524)
				(type default)
			)
			(layer "F.SilkS")
		)
		(fp_line
			(start -0.508 -0.9398)
			(end -0.508 0.9398)
			(stroke
				(width 0.1524)
				(type default)
			)
			(layer "F.SilkS")
		)
		(fp_rect
			(start -0.508 0.9398)
			(end 0.508 -0.9398)
			(stroke
				(width 0)
				(type default)
			)
			(fill no)
			(layer "F.CrtYd")
		)
		(fp_rect
			(start -0.508 0.9398)
			(end 0.508 -0.9398)
			(stroke
				(width 0)
				(type default)
			)
			(fill no)
			(layer "F.Fab")
		)
		(pad "1" smd custom
			(at 0 -0.4445 90)
			(size 0.1397 0.1397)
			(layers "F.Cu" "F.Mask" "F.Paste")
			(net "P3V3_STBY")
			(options
				(clearance outline)
				(anchor circle)
			)
			(primitives
				(gr_poly
					(pts
						(arc
							(start -0.1778 -0.2794)
							(mid -0.249642 -0.249642)
							(end -0.2794 -0.1778)
						)
						(arc
							(start -0.2794 0.1778)
							(mid -0.249642 0.249642)
							(end -0.1778 0.2794)
						)
						(arc
							(start 0.1778 0.2794)
							(mid 0.249642 0.249642)
							(end 0.2794 0.1778)
						)
						(arc
							(start 0.2794 -0.1778)
							(mid 0.249642 -0.249642)
							(end 0.1778 -0.2794)
						)
					)
					(width 0)
					(fill yes)
				)
			)
		)
		(pad "2" smd custom
			(at 0 0.4445 90)
			(size 0.1397 0.1397)
			(layers "F.Cu" "F.Mask" "F.Paste")
			(net "ROMA2")
			(options
				(clearance outline)
				(anchor circle)
			)
			(primitives
				(gr_poly
					(pts
						(arc
							(start -0.1778 -0.2794)
							(mid -0.249642 -0.249642)
							(end -0.2794 -0.1778)
						)
						(arc
							(start -0.2794 0.1778)
							(mid -0.249642 0.249642)
							(end -0.1778 0.2794)
						)
						(arc
							(start 0.1778 0.2794)
							(mid 0.249642 0.249642)
							(end 0.2794 0.1778)
						)
						(arc
							(start 0.2794 -0.1778)
							(mid 0.249642 -0.249642)
							(end 0.1778 -0.2794)
						)
					)
					(width 0)
					(fill yes)
				)
			)
		)
	)
	(footprint ""
		(layer "F.Cu")
		(at 262.001 -32.639 90)
		(property "Reference" "PR38"
			(at 0 0 90)
			(layer "F.SilkS")
			(hide yes)
			(effects
				(font
					(size 1.27 1.27)
				)
			)
		)
		(property "Value" "1K4R2F-1-GP"
			(at 0.064008 -3.993896 90)
			(unlocked yes)
			(layer "F.Fab")
			(hide yes)
			(effects
				(font
					(size 1.016 1.016)
					(thickness 0.1524)
				)
			)
		)
		(property "Device Type" "R402H16"
			(at 0.064008 -5.517896 90)
			(unlocked yes)
			(layer "F.Fab")
			(hide yes)
			(effects
				(font
					(size 1.016 1.016)
					(thickness 0.1524)
				)
			)
		)
		(duplicate_pad_numbers_are_jumpers no)
		(fp_line
			(start 0.508 -0.9398)
			(end -0.508 -0.9398)
			(stroke
				(width 0.1524)
				(type default)
			)
			(layer "F.SilkS")
		)
		(fp_line
			(start -0.508 -0.9398)
			(end -0.508 0.9398)
			(stroke
				(width 0.1524)
				(type default)
			)
			(layer "F.SilkS")
		)
		(fp_rect
			(start -0.508 0.9398)
			(end 0.508 -0.9398)
			(stroke
				(width 0)
				(type default)
			)
			(fill no)
			(layer "F.CrtYd")
		)
		(fp_rect
			(start -0.508 0.9398)
			(end 0.508 -0.9398)
			(stroke
				(width 0)
				(type default)
			)
			(fill no)
			(layer "F.Fab")
		)
		(pad "1" smd custom
			(at 0 -0.4445 90)
			(size 0.1397 0.1397)
			(layers "F.Cu" "F.Mask" "F.Paste")
			(net "P5V_STBY")
			(options
				(clearance outline)
				(anchor circle)
			)
			(primitives
				(gr_poly
					(pts
						(arc
							(start -0.1778 -0.2794)
							(mid -0.249642 -0.249642)
							(end -0.2794 -0.1778)
						)
						(arc
							(start -0.2794 0.1778)
							(mid -0.249642 0.249642)
							(end -0.1778 0.2794)
						)
						(arc
							(start 0.1778 0.2794)
							(mid 0.249642 0.249642)
							(end 0.2794 0.1778)
						)
						(arc
							(start 0.2794 -0.1778)
							(mid 0.249642 -0.249642)
							(end 0.1778 -0.2794)
						)
					)
					(width 0)
					(fill yes)
				)
			)
		)
		(pad "2" smd custom
			(at 0 0.4445 90)
			(size 0.1397 0.1397)
			(layers "F.Cu" "F.Mask" "F.Paste")
			(net "P1V8_STBY_EN")
			(options
				(clearance outline)
				(anchor circle)
			)
			(primitives
				(gr_poly
					(pts
						(arc
							(start -0.1778 -0.2794)
							(mid -0.249642 -0.249642)
							(end -0.2794 -0.1778)
						)
						(arc
							(start -0.2794 0.1778)
							(mid -0.249642 0.249642)
							(end -0.1778 0.2794)
						)
						(arc
							(start 0.1778 0.2794)
							(mid 0.249642 0.249642)
							(end 0.2794 0.1778)
						)
						(arc
							(start 0.2794 -0.1778)
							(mid 0.249642 -0.249642)
							(end 0.1778 -0.2794)
						)
					)
					(width 0)
					(fill yes)
				)
			)
		)
	)
	(footprint ""
		(layer "F.Cu")
		(at 97.54997 -79.121)
		(property "Reference" "STP150"
			(at 0 0 0)
			(layer "F.SilkS")
			(hide yes)
			(effects
				(font
					(size 1.27 1.27)
				)
			)
		)
		(property "Value" "TPAD28"
			(at 0.0127 -1.8034 0)
			(unlocked yes)
			(layer "F.Fab")
			(hide yes)
			(effects
				(font
					(size 1.016 1.016)
					(thickness 0.1524)
				)
			)
		)
		(property "Device Type" "TPAD28"
			(at 0.0127 -3.3274 0)
			(unlocked yes)
			(layer "F.Fab")
			(hide yes)
			(effects
				(font
					(size 1.016 1.016)
					(thickness 0.1524)
				)
			)
		)
		(duplicate_pad_numbers_are_jumpers no)
		(fp_poly
			(pts
				(arc
					(start 0.3556 0)
					(mid -0.3556 0)
					(end 0.3556 0)
				)
			)
			(stroke
				(width 0)
				(type default)
			)
			(fill no)
			(layer "F.CrtYd")
		)
		(fp_poly
			(pts
				(arc
					(start 0.6096 0)
					(mid -0.6096 0)
					(end 0.6096 0)
				)
			)
			(stroke
				(width 0)
				(type default)
			)
			(fill no)
			(layer "F.Fab")
		)
		(pad "1" smd circle
			(at 0 0)
			(size 0.7112 0.7112)
			(layers "F.Cu" "F.Mask" "F.Paste")
			(net "JTAG_EXP_TCK")
		)
	)
	(footprint ""
		(layer "F.Cu")
		(at 316.611 -114.681 90)
		(property "Reference" "PR35"
			(at 0 0 90)
			(layer "F.SilkS")
			(hide yes)
			(effects
				(font
					(size 1.27 1.27)
				)
			)
		)
		(property "Value" "619KR2F-GP"
			(at 0.064008 -3.993896 90)
			(unlocked yes)
			(layer "F.Fab")
			(hide yes)
			(effects
				(font
					(size 1.016 1.016)
					(thickness 0.1524)
				)
			)
		)
		(property "Device Type" "R402H16"
			(at 0.064008 -5.517896 90)
			(unlocked yes)
			(layer "F.Fab")
			(hide yes)
			(effects
				(font
					(size 1.016 1.016)
					(thickness 0.1524)
				)
			)
		)
		(duplicate_pad_numbers_are_jumpers no)
		(fp_line
			(start 0.508 -0.9398)
			(end -0.508 -0.9398)
			(stroke
				(width 0.1524)
				(type default)
			)
			(layer "F.SilkS")
		)
		(fp_line
			(start -0.508 -0.9398)
			(end -0.508 0.9398)
			(stroke
				(width 0.1524)
				(type default)
			)
			(layer "F.SilkS")
		)
		(fp_rect
			(start -0.508 0.9398)
			(end 0.508 -0.9398)
			(stroke
				(width 0)
				(type default)
			)
			(fill no)
			(layer "F.CrtYd")
		)
		(fp_rect
			(start -0.508 0.9398)
			(end 0.508 -0.9398)
			(stroke
				(width 0)
				(type default)
			)
			(fill no)
			(layer "F.Fab")
		)
		(pad "1" smd custom
			(at 0 -0.4445 90)
			(size 0.1397 0.1397)
			(layers "F.Cu" "F.Mask" "F.Paste")
			(net "AGND_P3V3_STBY")
			(options
				(clearance outline)
				(anchor circle)
			)
			(primitives
				(gr_poly
					(pts
						(arc
							(start -0.1778 -0.2794)
							(mid -0.249642 -0.249642)
							(end -0.2794 -0.1778)
						)
						(arc
							(start -0.2794 0.1778)
							(mid -0.249642 0.249642)
							(end -0.1778 0.2794)
						)
						(arc
							(start 0.1778 0.2794)
							(mid 0.249642 0.249642)
							(end 0.2794 0.1778)
						)
						(arc
							(start 0.2794 -0.1778)
							(mid 0.249642 -0.249642)
							(end 0.1778 -0.2794)
						)
					)
					(width 0)
					(fill yes)
				)
			)
		)
		(pad "2" smd custom
			(at 0 0.4445 90)
			(size 0.1397 0.1397)
			(layers "F.Cu" "F.Mask" "F.Paste")
			(net "P3V3_STBY_RF")
			(options
				(clearance outline)
				(anchor circle)
			)
			(primitives
				(gr_poly
					(pts
						(arc
							(start -0.1778 -0.2794)
							(mid -0.249642 -0.249642)
							(end -0.2794 -0.1778)
						)
						(arc
							(start -0.2794 0.1778)
							(mid -0.249642 0.249642)
							(end -0.1778 0.2794)
						)
						(arc
							(start 0.1778 0.2794)
							(mid 0.249642 0.249642)
							(end 0.2794 0.1778)
						)
						(arc
							(start 0.2794 -0.1778)
							(mid 0.249642 -0.249642)
							(end 0.1778 -0.2794)
						)
					)
					(width 0)
					(fill yes)
				)
			)
		)
	)
)
